# BASEBOARD_FAB2 (Tioga Pass) — schematic parts with pin connectivity, parts 4718–4743 of 4751; source: Cadence DE-HDL packaged netlist (pstxprt.dat, pstxnet.dat, pstchip.dat)

U25W4  AST2520A1-GP-GP  pkg ASIC2-GB1  page 143  (pins 307-456 of 456)
  N17  PV33D7  POWER  = VCC_D_3V3
  N18  GPIOAA6_VPOR8_NORD6_SALT13  BI  = IRQ_LOM_ALERT_N
  N19  \gpioab0_vpode_noroe#\  BI  = IRQ_HSC_FAULT_N
  N20  \gpioq7_pewake#\  BI  = FM_PE_BMC_WAKE_N
  N21  GPIOQ4_SCL14  BI  = FM_UARTSW_LSB_N
  N22  GPIOQ5_SDA14  BI  = FM_UARTSW_MSB_N
  P1  GPIOK5_SDA7  BI  = SMB_SENSOR_BMC_STBY_LVC3_SDA
  P2  GPIOK6_SCL8  BI  = SMB_BMC_PMBUS_STBY_LVC3_SCL_R
  P3  GPIOL5_NRTS1_VPICLK  BI  = FM_PMBUS_ALERT_BUF_EN_R3_N
  P4  GPIOL4_NDTR1_VPIVS  BI  = FM_MEM_THERM_EVENT_PCH_N
  P5  GPIOM5_NRTS2_VPIB7  BI  = FM_CPU1_THERMTRIP_LATCH_LVT3_N
  P6  PV33D10  POWER  = VCC_D_3V3
  P7  IV11D21  POWER  = P1V15_AUX_BMC
  P9  IV11D22  POWER  = P1V15_AUX_BMC
  P10  IV11D15  POWER  = P1V15_AUX_BMC
  P11  IV11D16  POWER  = P1V15_AUX_BMC
  P12  IV11D17  POWER  = P1V15_AUX_BMC
  P13  IV11D18  POWER  = P1V15_AUX_BMC
  P14  IV11D19  POWER  = P1V15_AUX_BMC
  P16  IV11D20  POWER  = P1V15_AUX_BMC
  P17  PV33D9  POWER  = VCC_D_3V3
  P18  GPIOS3_VPOB5_SALT6  BI  = HSC_SMBUS_SWITCH_EN
  P19  GPIOAA7_VPOR9_NORD7_SALT14  BI  = FM_BIOS_POST_CMPLT_N
  P20  GPIOY7_SDA2  BI  = SMB_SLOTX24_STBY_LVC3_SDA_R
  P21  \gpioy3_sioonctrl#\  BI  = FM_BMC_ONCTL_R_N
  P22  \gpioy2_siopwreq#\  BI  = BMC_JTAG_SEL_N
  R1  GPIOK7_SDA8  BI  = SMB_BMC_PMBUS_STBY_LVC3_SDA_R
  R2  GPIOJ0_SGPMCK  BI  = SGPIO_BMC_CLK_R
  R3  GPIOJ6_DDCCLK  BI  = I2C_BMC_VGA_DDC_SCL
  R4  GPIOJ5_VGAVS  BI  = BMC_VGA_VSYNC
  R5  GPIOM6_TXD2_VPIB8  BI  = SP2_BMC_CM_UART_TX
  R6  PV33D12  POWER  = VCC_D_3V3
  R7  IV11D24  POWER  = P1V15_AUX_BMC
  R16  IV11D23  POWER  = P1V15_AUX_BMC
  R17  PV33D11  POWER  = VCC_D_3V3
  R18  GPIOS2_VPOB4_SALT5  BI  = IRQ_SML0_ALERT_N
  R19  GPIOS4_VPOB6  BI  = BMC_STRAP_BIT3
  R20  GPIOAB3_VPOCLK_WDTRST2  BI  = NC
  R21  \gpioy1_sios5#\  BI  = FM_SLPS4_N
  R22  \gpioy0_sios3#\  BI  = FM_SLPS3_N
  T1  GPIOL1_NDCD1_VPIDE  BI  = IRQ_OC_DETECT_N
  T2  GPIOL0_NCTS1  BI  = IRQ_UV_DETECT_N
  T3  GPIOJ7_DDCDAT  BI  = I2C_BMC_VGA_DDC_SDA
  T4  GPION7_PWM7_VPIG7  BI  = FM_PWRBRK_N
  T5  GPIOM7_RXD2_VPIB9  BI  = SP2_BMC_CM_UART_RX
  T6  GND59  POWER  = GND
  T7  GND60  POWER  = GND
  T8  MVDD4  POWER  = P1V2_AUX_BMC
  T9  MVREF  UNSPEC  = BMC_M_VREFCA
  T10  MVDD0  POWER  = P1V2_AUX_BMC
  T11  PV33D13  POWER  = VCC_PA_3V3
  T12  MVDD1  POWER  = P1V2_AUX_BMC
  T13  MVDD2  POWER  = P1V2_AUX_BMC
  T14  MVDD3  POWER  = P1V2_AUX_BMC
  T15  PV33D14  POWER  = VCC_D_3V3
  T16  GND58  POWER  = GND
  T17  \gpior2_spi2cs0#\  BI  = BMC_TCK_MUX_SEL
  T18  FWSPIMISO  BI  = SPI_BMC_BT_DI
  T19  \gpior1_fwspics2#\  BI  = FM_MP_PS_REDUNDANT_LOST_N
  T20  GPIOAA5_VPOR7_NORD5_SALT12  BI  = UV_HIGH_SET
  T21  \gpioab1_vpohs_norwe#\  BI  = FM_OCP_MEZZA_PRES
  T22  GPIOAB2_VPOVS_WDTRST1  BI  = BMC_SELF_HW_RST
  U1  GPIOL2_NDSR1  BI  = FM_HSC_TIMER_EXP_N
  U2  GPIOL3_NRI1_VPIHS  BI  = FM_BIOS_TOP_SWAP
  U3  GPION3_PWM3_VPIG3  BI  = FM_CPU_MSMI_LVT3_N
  U4  GPIOO1_TACH1_VPIG9  BI  = FAN_TACH1
  U5  GPIOO0_TACH0_VPIG8  BI  = FAN_TACH0
  U6  GND62  POWER  = GND
  U7  MDQ15  BI  = BMC_M_DQ15
  U8  MDM0  OUT  = BMC_M_DM0
  U9  MDQ4  BI  = BMC_M_DQ4
  U10  MDQ0  BI  = BMC_M_DQ0
  U11  GND61  POWER  = GND
  U12  MBA0  OUT  = BMC_M_BA0
  U13  MA10  OUT  = BMC_M_A10
  U14  MA3  OUT  = BMC_M_A3
  U15  MA15  OUT  = TP_BMC_M_A15
  U16  \malert#\  BI  = BMC_M_MALERT_N
  U17  FWSPIMOSI  BI  = SPI_BMC_BT_DO_R
  U18  \srst#\  IN  = RST_BMC_SRST_N
  U19  GPIOS1_VPOB3_BMCINT  BI  = FM_BMC_READY_N
  U20  GPIOS6_VPOB8  BI  = BMC_STRAP_BIT5
  U21  GPIOZ4_VPOG6_NORA4  BI  = BMC_STRAP_BIT17
  U22  GPIOAA4_VPOR6_NORD4_SALT11  BI  = PECI_SEL
  V1  GPIOL6_TXD1  BI  = SP1_BMC_HOST_UART_TX
  V2  GPION0_PWM0  BI  = FAN_PWM_OUT_SYS0
  V3  GPION2_PWM2_VPIG2  BI  = FM_BIOS_PREFRB2_GOOD
  V4  GPIOP0_TACH8_VPIR6  BI  = FM_BOARD_SKU_ID0
  V5  GPIOO2_TACH2  BI  = FAN_TACH2
  V6  GPIOP7_TACH15  BI  = BMC_RSMRST_B_N
  V7  MDQ14  BI  = BMC_M_DQ14
  V8  GND67  POWER  = GND
  V9  MDQ7  BI  = BMC_M_DQ7
  V10  GND63  POWER  = GND
  V11  MODT  OUT  = BMC_M_ODT
  V12  GND64  POWER  = GND
  V13  MA0  OUT  = BMC_M_A0
  V14  GND65  POWER  = GND
  V15  MA5  OUT  = BMC_M_A5
  V16  GND66  POWER  = GND
  V17  PLLDV11  POWER  = P1V15_AUX_BMC
  V18  \extrst#\  IN  = RST_BMC_EXTRST_N
  V19  GPIOR5_SPI2MISO  BI  = RST_BMC_PLTRST_BUF_N
  V20  \gpios0_vpob2_spi2cs1#\  BI  = FM_THROTTLE_N
  V21  GPIOAA1_VPOR3_NORD1_SALT8  BI  = IRQ_SML1_PMBUS_ALERT_N
  V22  GPIOZ6_VPOG8_NORA6  BI  = BMC_STRAP_BIT20
  W1  GPIOL7_RXD1  BI  = SP1_BMC_HOST_UART_RX
  W2  GPION1_PWM1  BI  = FAN_PWM_OUT_SYS1
  W3  GPION4_PWM4_VPIG4  BI  = FM_BACKUP_BIOS_SEL_N
  W4  GPIOO7_TACH7_VPIR5  BI  = FM_XRC_READY_N
  W5  GPIOP1_TACH9_VPIR7  BI  = FM_BOARD_SKU_ID1
  W6  GPIOP6_TACH14  BI  = BMC_PWR_DEBUG_N
  W7  MDQ13  BI  = BMC_M_DQ13
  W8  MDQ11  BI  = BMC_M_DQ11
  W9  MDQ6  BI  = BMC_M_DQ6
  W10  MDQ1  BI  = BMC_M_DQ1
  W11  MIOZ  UNSPEC  = BMC_MIOZ
  W12  \mras#\  OUT  = BMC_M_RAS_N
  W13  MBA2_MBG0  OUT  = BMC_M_BG0
  W14  MA2  OUT  = BMC_M_A2
  W15  MA4  OUT  = BMC_M_A4
  W16  MA8  OUT  = BMC_M_A8
  W17  PLLAV331  POWER  = VCC_PA_3V3
  W18  CLKIN  IN  = CLK_24M_25M_BMC_CLKIN
  W19  GPIOR4_SPI2MOSI  BI  = XDP_PRESENT_N
  W20  GPIOS5_VPOB7  BI  = NC
  W21  GPIOZ7_VPOG9_NORA7  BI  = BMC_STRAP_BIT27
  W22  GPIOZ5_VPOG7_NORA5  BI  = BMC_STRAP_BIT18
  Y1  GPIOM0_NCTS2_VPIB2  BI  = FM_CPU0_RC_ERROR_N
  Y2  GPIOM3_NRI2_VPIB5  BI  = FM_OC_DETECT_EN_N
  Y3  GPION6_PWM6_VPIG6  BI  = PUMP_PWM_OUT
  Y4  GPIOO5_TACH5_VPIR3  BI  = PUMP_TACH1
  Y5  GPIOP5_TACH13  BI  = BMC_PREQ_N
  Y6  GPIOP4_TACH12  BI  = FM_BOARD_SKU_ID4
  Y7  MDQ10  BI  = BMC_M_DQ10
  Y8  MDQ9  BI  = BMC_M_DQ9
  Y9  MDQ5  BI  = BMC_M_DQ5
  Y10  MDQ2  BI  = BMC_M_DQ2
  Y11  MCKE  OUT  = BMC_M_CKE
  Y12  \mwe#\  OUT  = BMC_M_WE_N
  Y13  MBA1  OUT  = BMC_M_BA1
  Y14  MA12  OUT  = BMC_M_A12
  Y15  \ma14_mact#\  OUT  = BMC_M_MACT_N
  Y16  MA9  OUT  = BMC_M_A9
  Y17  PLLAV330  POWER  = VCC_PA_3V3
  Y18  \hbled#\  OUT  = FM_BMC_HEARTBEAT_N
  Y19  GPIOR3_SPI2CK  BI  = BMC_PRDY_N
  Y20  \gpioz0_vpog2_nora0_siopbi#\  BI  = FM_BMC_CPLD_GPO
  Y21  GPIOAA0_VPOR2_NORD0_SALT7  BI  = FM_CPU1_SKTOCC_LVT3_N
  Y22  GPIOAA2_VPOR4_NORD2_SALT9  BI  = FP_PWR_ID_LED_N

U25W5  H5AN4G6NAFR-TFC-GP  pkg MEMORY-G2  page 151
  A1  VDDQ(0)  POWER  = P1V2_AUX_BMC
  A2  VSSQ(0)  POWER  = GND
  A3  DQU0  UNSPEC  = BMC_M_DQ8
  A7  DQSU_C  BI  = BMC_M_DQS1_DN
  A8  VSSQ(1)  POWER  = GND
  A9  VDDQ(1)  POWER  = P1V2_AUX_BMC
  B1  VPP(0)  POWER  = P2V5_AUX_BMC
  B2  VSS(0)  POWER  = GND
  B3  VDD(0)  POWER  = P1V2_AUX_BMC
  B7  DQSU_T  BI  = BMC_M_DQS1_DP
  B8  DQU1  UNSPEC  = BMC_M_DQ9
  B9  VDD(1)  POWER  = P1V2_AUX_BMC
  C1  VDDQ(2)  POWER  = P1V2_AUX_BMC
  C2  DQU4  UNSPEC  = BMC_M_DQ12
  C3  DQU2  UNSPEC  = BMC_M_DQ10
  C7  DQU3  UNSPEC  = BMC_M_DQ11
  C8  DQU5  UNSPEC  = BMC_M_DQ13
  C9  VSSQ(2)  POWER  = GND
  D1  VDD(2)  POWER  = P1V2_AUX_BMC
  D2  VSSQ(3)  POWER  = GND
  D3  DQU6  UNSPEC  = BMC_M_DQ14
  D7  DQU7  UNSPEC  = BMC_M_DQ15
  D8  VSSQ(4)  POWER  = GND
  D9  VDDQ(3)  POWER  = P1V2_AUX_BMC
  E1  VSS(1)  POWER  = GND
  E2  \dmu#/dbiu#\  BI  = BMC_M_DM1
  E3  VSSQ(5)  POWER  = GND
  E7  \dml#/dbil#\  BI  = BMC_M_DM0
  E8  VSSQ(6)  POWER  = GND
  E9  VSS(2)  POWER  = GND
  F1  VSSQ(7)  POWER  = GND
  F2  VDDQ(4)  POWER  = P1V2_AUX_BMC
  F3  DQSL_C  BI  = BMC_M_DQS0_DN
  F7  DQL1  UNSPEC  = BMC_M_DQ1
  F8  VDDQ(5)  POWER  = P1V2_AUX_BMC
  F9  ZQ  UNSPEC  = BMC_ZQ
  G1  VDDQ(6)  POWER  = P1V2_AUX_BMC
  G2  DQL0  UNSPEC  = BMC_M_DQ0
  G3  DQSL_T  BI  = BMC_M_DQS0_DP
  G7  VDD(3)  POWER  = P1V2_AUX_BMC
  G8  VSS(3)  POWER  = GND
  G9  VDDQ(7)  POWER  = P1V2_AUX_BMC
  H1  VSSQ(8)  POWER  = GND
  H2  DQL4  UNSPEC  = BMC_M_DQ4
  H3  DQL2  UNSPEC  = BMC_M_DQ2
  H7  DQL3  UNSPEC  = BMC_M_DQ3
  H8  DQL5  UNSPEC  = BMC_M_DQ5
  H9  VSSQ(9)  POWER  = GND
  J1  VDD(4)  POWER  = P1V2_AUX_BMC
  J2  VDDQ(8)  POWER  = P1V2_AUX_BMC
  J3  DQL6  UNSPEC  = BMC_M_DQ6
  J7  DQL7  UNSPEC  = BMC_M_DQ7
  J8  VDDQ(9)  POWER  = P1V2_AUX_BMC
  J9  VDD(5)  POWER  = P1V2_AUX_BMC
  K1  VSS(4)  POWER  = GND
  K2  CKE  IN  = BMC_M_CKE
  K3  ODT  IN  = BMC_M_ODT
  K7  CK_T  IN  = BMC_M_CLK_DP
  K8  CK_C  IN  = BMC_M_CLK_DN
  K9  VSS(5)  POWER  = GND
  L1  VDD(6)  POWER  = P1V2_AUX_BMC
  L2  \we#/a14\  IN  = BMC_M_WE_N
  L3  \act#\  IN  = BMC_M_MACT_N
  L7  \cs#\  IN  = BMC_M_CS_N
  L8  \ras#/a16\  IN  = BMC_M_RAS_N
  L9  VDD(7)  POWER  = P1V2_AUX_BMC
  M1  VREFCA  UNSPEC  = BMC_M_VREFCA
  M2  BG0  IN  = BMC_M_BG0
  M3  \a10/ap\  IN  = BMC_M_A10
  M7  \a12/bc#\  IN  = BMC_M_A12
  M8  \cas#/a15\  IN  = BMC_M_CAS_N
  M9  VSS(6)  POWER  = GND
  N1  VSS(7)  POWER  = GND
  N2  BA0  IN  = BMC_M_BA0
  N3  A4  IN  = BMC_M_A4
  N7  A3  IN  = BMC_M_A3
  N8  BA1  IN  = BMC_M_BA1
  N9  TEN  IN  = GND
  P1  \reset#\  IN  = BMC_M_RST_N
  P2  A6  IN  = BMC_M_A6
  P3  A0  IN  = BMC_M_A0
  P7  A1  IN  = BMC_M_A1
  P8  A5  IN  = BMC_M_A5
  P9  \alert#\  OUT  = BMC_M_MALERT_N
  R1  VDD(8)  POWER  = P1V2_AUX_BMC
  R2  A8  IN  = BMC_M_A8
  R3  A2  IN  = BMC_M_A2
  R7  A9  IN  = BMC_M_A9
  R8  A7  IN  = BMC_M_A7
  R9  VPP(1)  POWER  = P2V5_AUX_BMC
  T1  VSS(8)  POWER  = GND
  T2  A11  IN  = BMC_M_A11
  T3  PAR  IN  = BMC_M_PAR
  T7  \nc#t7\  UNSPEC  = NC
  T8  A13  IN  = BMC_M_A13
  T9  VDD(9)  POWER  = P1V2_AUX_BMC

U25W7  U74AHCT1G125G-AL5-R-GP-U  pkg TTL-G4  page 252
  1  \oe#\  UNSPEC  = GND
  2  A  UNSPEC  = BMC_VGA_HSYNC
  3  GND  POWER  = GND
  4  Y  UNSPEC  = VGA_REAR_HSYNC_S
  5  VCC  POWER  = P5V_VGA_D

U25W8  U74AHCT1G125G-AL5-R-GP-U  pkg TTL-G4  page 252
  1  \oe#\  UNSPEC  = GND
  2  A  UNSPEC  = BMC_VGA_VSYNC
  3  GND  POWER  = GND
  4  Y  UNSPEC  = VGA_REAR_VSYNC_S
  5  VCC  POWER  = P5V_VGA_D

U25W9  TTL1G07_A  74LVC1G07 IC  pkg SOP  page 157 : 2 = PWRGD_DSW_PWROK ; 4 = RST_BMC_SRST_N

U25W10  GTL2014  IC  pkg SM  page 254
  1  DIR  IN  = PU_GTL2014_3_DIR
  2  B0  BI  = XDP_PREQ_N
  3  B1  BI  = XDP_CPU_PWR_DEBUG_N
  4  VREF  POWER  = PD_GTL2014_3_VREF
  5  B2  BI  = XDP_TDI_R
  6  B3  BI  = XDP_TMS_R
  7  GND(0)  GROUND  = GND
  8  GND(1)  GROUND  = GND
  9  A3  BI  = JTAG_BMC_BUF_TMS
  10  A2  BI  = JTAG_BMC_BUF_TDI
  11  GND(2)  GROUND  = GND
  12  A1  BI  = BMC_PWR_DEBUG_BUF_N
  13  A0  BI  = BMC_PREQ_BUF_N
  14  VCC  POWER  = P3V3_STBY

U25W11  GTL2014  IC  pkg SM  page 255
  1  DIR  IN  = PD_GTL2014_DIR_6
  2  B0  BI  = PD_GTL2014_6_B0
  3  B1  BI  = XDP_PRDY_N
  4  VREF  POWER  = P0V7_GTL2014_VREF_6
  5  B2  BI  = PD_GTL2014_6_B2
  6  B3  BI  = XDP_TDO
  7  GND(0)  GROUND  = GND
  8  GND(1)  GROUND  = GND
  9  A3  BI  = JTAG_BMC_BUF_TDO_R
  10  A2  BI  = TP_GTL2014_6_A2
  11  GND(2)  GROUND  = GND
  12  A1  BI  = BMC_PRDY_N
  13  A0  BI  = TP_GTL2014_6_A0
  14  VCC  POWER  = P3V3_STBY

U25W12  TTL3126  74CBTLV3126 IC  pkg QFNLF  page 254
  1  OE(3)  = BMC_JTAG_SEL_BUF
  2  A(3)  = BMC_PREQ_N
  3  B(3)  = BMC_PREQ_BUF_N
  4  OE(2)  = JTAG_BMC_TCK0
  5  A(2)  = P1V05_PCH_STBY
  6  B(2)  = XDP_CPU_TCK0_R
  8  B(1)  = XDP_PCH_TCK1_R
  9  A(1)  = P1V05_PCH_STBY
  10  OE(1)  = JTAG_BMC_TCK1
  11  B(0)  BI  = XDP_TRST_R_N
  12  A(0)  BI  = P1V05_PCH_STBY
  13  OE(0)  IN  = JTAG_BMC_TRST_BUF_N

U25W13  MAX4564EKA-GP  pkg SCRET-GC1  page 254
  1  NC  UNSPEC  = JTAG_BMC_TCK0
  2  \v+\  POWER  = P3V3_STBY
  3  \in\  IN  = BMC_TCK_MUX_SEL
  4  NO  UNSPEC  = JTAG_BMC_TCK1
  5  GND  POWER  = GND
  6  \v-\  POWER  = GND
  7  \en#\  UNSPEC  = BMC_JTAG_SEL_N
  8  COM  UNSPEC  = JTAG_BMC_TCK_BUF

U25W14  TTL1G07_A  74LVC1G07 IC  pkg SOP  page 255 : 2 = XDP_PRESENT_N ; 4 = CPU_XDP_PRESENT_N
U25W15  TTL1G07_A  74LVC1G07 IC  pkg SOP  page 255 : 2 = BMC_DEBUG_EN_N ; 4 = CPU_XDP_PRESENT_N

U25W16  TTL3126  74CBTLV3126 IC  pkg QFNLF  page 255
  1  OE(3)  = BMC_JTAG_SEL_BUF
  2  A(3)  = JTAG_BMC_TDI
  3  B(3)  = JTAG_BMC_BUF_TDI
  4  OE(2)  = BMC_JTAG_SEL_BUF
  5  A(2)  = JTAG_BMC_TMS
  6  B(2)  = JTAG_BMC_BUF_TMS
  8  B(1)  = JTAG_BMC_BUF_TDO
  9  A(1)  = JTAG_BMC_TDO
  10  OE(1)  = BMC_JTAG_SEL_BUF
  11  B(0)  BI  = BMC_PWR_DEBUG_BUF_N
  12  A(0)  BI  = BMC_PWR_DEBUG_N
  13  OE(0)  IN  = BMC_JTAG_SEL_BUF

U25W17  TTL1G08  NC7SZ08 IC  pkg SOTLF  page 254
  1  A(0)  IN  = JTAG_BMC_TRST_N
  2  B(0)  IN  = BMC_JTAG_SEL_BUF
  4  Y(0)  OUT  = JTAG_BMC_TRST_BUF_N

U25W18  TTL1G08  NC7SZ08 IC  pkg SOTLF  page 255
  1  A(0)  IN  = XDP_PRESENT_N
  2  B(0)  IN  = BMC_JTAG_SEL
  4  Y(0)  OUT  = BMC_JTAG_SEL_BUF

U25W19  TTL1G126_A  74HC1G126 IC  pkg SOT  page 254
  1  OE  IN  = BMC_JTAG_SEL_BUF
  2  A  IN  = JTAG_BMC_TCK
  4  Y  OUT  = JTAG_BMC_TCK_BUF

U32W1  TCA9517DGKR-GP  pkg DISCRET-G8  page 185
  1  VCCA  POWER  = P1V8_M2
  2  SCLA  UNSPEC  = SMB_M2_SCL_R
  3  SDAA  UNSPEC  = SMB_M2_SDA_R
  4  GND  POWER  = GND
  5  EN  UNSPEC  = PD_SMB_M2_EN
  6  SDAB  UNSPEC  = SMB_OCP_LAN_STBY_LVC3_SDA
  7  SCLB  UNSPEC  = SMB_OCP_LAN_STBY_LVC3_SCL
  8  VCCB  POWER  = P3V3_STBY

U32W2  TCA9517DGKR-GP  pkg DISCRET-G8  page 185
  1  VCCA  POWER  = P1V8_M2
  2  SCLA  UNSPEC  = SMB_M2_ALT_R_N
  3  SDAA  UNSPEC  = NC
  4  GND  POWER  = GND
  5  EN  UNSPEC  = PD_SMB_M2_EN
  6  SDAB  UNSPEC  = NC
  7  SCLB  UNSPEC  = IRQ_MEZZ_LAN_ALERT_N
  8  VCCB  POWER  = P3V3_STBY

UN8F2  W25Q256  IC  pkg XSOI  page 246
  1  HOLD_N_IO(3)  BI  = PU_TPM_SPI_BMC_HOLD_N
  2  VCC  POWER  = P3V3_STBY
  3  RESET_N  IN  = PU_TPM_SPI_FLASH_RESET_2_N
  4  NC(6)  NC  = TP_TPM_SPI_6
  5  NC(5)  NC  = TP_TPM_SPI_5
  6  NC(4)  NC  = TP_TPM_SPI_4
  7  CS_N  IN  = SPI_BMC_BT_CS0_N
  8  DO_IO(1)  BI  = SPI_TPM_BMC_DI_R
  9  WP_N_IO(2)  BI  = TPM_SPI_BMC_WP_N
  10  GND  GROUND  = GND
  11  NC(3)  NC  = TP_TPM_SPI_3
  12  NC(2)  NC  = TP_TPM_SPI_2
  13  NC(1)  NC  = TP_TPM_SPI_1
  14  NC(0)  NC  = TP_TPM_SPI_0
  15  DI_IO(0)  BI  = SPI_BMC_BT_DO
  16  CLK  IN  = SPI_BMC_BT_CLK

VR1D1  ZENER  13V IC  pkg SM  page 199 : 1 = P12V_PSU ; 2 = GND

VR32W1  LMV431AIMFX-GP  pkg DISCRET-G5  page 185
  1  REF  UNSPEC  = VREF_LMV431_1V42
  2  CATHODE  UNSPEC  = P1V8_M2
  3  ANODE  UNSPEC  = GND

WR8D30  RES  10.0K 1% CHIP  pkg 0402  page 89 : 1 = FM_ADR_COMPLETE_CPU1_N ; 2 = IRQ_DIMM_SAVE_CPU1_R_N

XBT8G1  VERT_BATT_3PIN  3PVERT  pkg PIP  page 196
  1  P1  UNSPEC  = P3V_BAT_SOURCE
  2  P2  UNSPEC  = P3V_BAT_SOURCE
  3  N  UNSPEC  = GND

XLU1  SOCKET_P_MECH_A  PLASTIC  pkg LEFT  page 21
XLU2  SOCKET_P_MECH_A  PLASTIC  pkg LEFT  page 55
XRU1  SOCKET_P_MECH_A  PLASTIC  pkg RIGHT  page 21
XRU2  SOCKET_P_MECH_A  PLASTIC  pkg RIGHT  page 55
